(kicad_pcb
	(version 20241229)
	(generator "pcbnew")
	(generator_version "9.0")
	(general
		(thickness 1.294)
		(legacy_teardrops no)
	)
	(paper "A3")
	(title_block
		(title "Kintex 410T devboard")
		(date "2024-04-03")
		(rev "1.1.2")
		(comment 9 "footprints 696-701 of 975")
	)
	(layers
		(0 "F.Cu" mixed)
		(4 "In1.Cu" power)
		(6 "In2.Cu" power)
		(8 "In3.Cu" mixed)
		(10 "In4.Cu" power)
		(12 "In5.Cu" mixed)
		(14 "In6.Cu" power)
		(16 "In7.Cu" mixed)
		(18 "In8.Cu" power)
		(2 "B.Cu" mixed)
		(9 "F.Adhes" user "F.Adhesive")
		(11 "B.Adhes" user "B.Adhesive")
		(13 "F.Paste" user)
		(15 "B.Paste" user)
		(5 "F.SilkS" user "F.Silkscreen")
		(7 "B.SilkS" user "B.Silkscreen")
		(1 "F.Mask" user)
		(3 "B.Mask" user)
		(17 "Dwgs.User" user "User.Drawings")
		(19 "Cmts.User" user "User.Comments")
		(21 "Eco1.User" user "User.Eco1")
		(23 "Eco2.User" user "User.Eco2")
		(25 "Edge.Cuts" user)
		(27 "Margin" user)
		(31 "F.CrtYd" user "F.Courtyard")
		(29 "B.CrtYd" user "B.Courtyard")
		(35 "F.Fab" user)
		(33 "B.Fab" user)
	)
	(footprint "antmicro-footprints:C_0402_1005Metric"
		(layer "B.Cu")
		(at 251.701 112.3 180)
		(descr "Capacitor SMD 0402")
		(tags "capacitor SMD 0402")
		(property "Reference" "C398"
			(at -3.799 -0.325 0)
			(layer "B.SilkS")
			(effects
				(font
					(size 0.7 0.7)
					(thickness 0.15)
				)
				(justify left bottom mirror)
			)
		)
		(property "Value" "C_100n_0402"
			(at 0 -1.169 0)
			(layer "B.Fab")
			(effects
				(font
					(size 0.7 0.7)
					(thickness 0.15)
				)
				(justify left bottom mirror)
			)
		)
		(property "Description" "SMD Multilayer Ceramic Capacitor, 0.1 µF, 50 V, 0402 [1005 Metric], ± 10%, X5R, GRM Series"
			(at 0 0 180)
			(layer "F.Fab")
			(hide yes)
			(effects
				(font
					(size 1.27 1.27)
					(thickness 0.15)
				)
			)
		)
		(property "Author" "Antmicro"
			(at 503.402 224.6 0)
			(layer "B.Fab")
			(hide yes)
			(effects
				(font
					(size 1 1)
					(thickness 0.15)
				)
				(justify mirror)
			)
		)
		(property "Dielectric" "X5R"
			(at 503.402 224.6 0)
			(layer "B.Fab")
			(hide yes)
			(effects
				(font
					(size 1 1)
					(thickness 0.15)
				)
				(justify mirror)
			)
		)
		(property "License" "Apache-2.0"
			(at 503.402 224.6 0)
			(layer "B.Fab")
			(hide yes)
			(effects
				(font
					(size 1 1)
					(thickness 0.15)
				)
				(justify mirror)
			)
		)
		(property "MPN" "GRM155R61H104KE14D"
			(at 503.402 224.6 0)
			(layer "B.Fab")
			(hide yes)
			(effects
				(font
					(size 1 1)
					(thickness 0.15)
				)
				(justify mirror)
			)
		)
		(property "Manufacturer" "Murata"
			(at 503.402 224.6 0)
			(layer "B.Fab")
			(hide yes)
			(effects
				(font
					(size 1 1)
					(thickness 0.15)
				)
				(justify mirror)
			)
		)
		(property "Val" "100n"
			(at 503.402 224.6 0)
			(layer "B.Fab")
			(hide yes)
			(effects
				(font
					(size 1 1)
					(thickness 0.15)
				)
				(justify mirror)
			)
		)
		(property "Voltage" "50V"
			(at 503.402 224.6 0)
			(layer "B.Fab")
			(hide yes)
			(effects
				(font
					(size 1 1)
					(thickness 0.15)
				)
				(justify mirror)
			)
		)
		(sheetname "HDMI + Ethernet")
		(sheetfile "hdmi-ethernet.kicad_sch")
		(attr smd)
		(fp_rect
			(start -0.925 0.47)
			(end 0.925 -0.47)
			(stroke
				(width 0.05)
				(type default)
			)
			(fill no)
			(layer "B.CrtYd")
		)
		(fp_line
			(start 0.504 0.25)
			(end 0.504 -0.248)
			(stroke
				(width 0.15)
				(type solid)
			)
			(layer "B.Fab")
		)
		(fp_line
			(start 0.504 -0.248)
			(end -0.494 -0.248)
			(stroke
				(width 0.15)
				(type solid)
			)
			(layer "B.Fab")
		)
		(fp_line
			(start -0.494 0.25)
			(end 0.504 0.25)
			(stroke
				(width 0.15)
				(type solid)
			)
			(layer "B.Fab")
		)
		(fp_line
			(start -0.494 -0.248)
			(end -0.494 0.25)
			(stroke
				(width 0.15)
				(type solid)
			)
			(layer "B.Fab")
		)
		(pad "1" smd roundrect
			(at -0.48 0 180)
			(size 0.59 0.64)
			(layers "B.Cu" "B.Mask" "B.Paste")
			(roundrect_rratio 0.25)
			(net 1 "GND")
			(pintype "passive")
		)
		(pad "2" smd roundrect
			(at 0.48 0 180)
			(size 0.59 0.64)
			(layers "B.Cu" "B.Mask" "B.Paste")
			(roundrect_rratio 0.25)
			(net 795 "/HDMI + Ethernet/HDMI_5V")
			(pintype "passive")
		)
	)
	(footprint "antmicro-footprints:C_0402_1005Metric"
		(layer "B.Cu")
		(at 173.15 141.7 180)
		(descr "Capacitor SMD 0402")
		(tags "capacitor SMD 0402")
		(property "Reference" "C294"
			(at -1.9 0.45 0)
			(layer "B.SilkS")
			(effects
				(font
					(size 0.7 0.7)
					(thickness 0.15)
				)
				(justify left bottom mirror)
			)
		)
		(property "Value" "C_100n_0402"
			(at 0 -1.169 0)
			(layer "B.Fab")
			(effects
				(font
					(size 0.7 0.7)
					(thickness 0.15)
				)
				(justify left bottom mirror)
			)
		)
		(property "Description" "SMD Multilayer Ceramic Capacitor, 0.1 µF, 50 V, 0402 [1005 Metric], ± 10%, X5R, GRM Series"
			(at 0 0 180)
			(layer "F.Fab")
			(hide yes)
			(effects
				(font
					(size 1.27 1.27)
					(thickness 0.15)
				)
			)
		)
		(property "Author" "Antmicro"
			(at 346.3 283.4 0)
			(layer "B.Fab")
			(hide yes)
			(effects
				(font
					(size 1 1)
					(thickness 0.15)
				)
				(justify mirror)
			)
		)
		(property "Dielectric" "X5R"
			(at 346.3 283.4 0)
			(layer "B.Fab")
			(hide yes)
			(effects
				(font
					(size 1 1)
					(thickness 0.15)
				)
				(justify mirror)
			)
		)
		(property "License" "Apache-2.0"
			(at 346.3 283.4 0)
			(layer "B.Fab")
			(hide yes)
			(effects
				(font
					(size 1 1)
					(thickness 0.15)
				)
				(justify mirror)
			)
		)
		(property "MPN" "GRM155R61H104KE14D"
			(at 346.3 283.4 0)
			(layer "B.Fab")
			(hide yes)
			(effects
				(font
					(size 1 1)
					(thickness 0.15)
				)
				(justify mirror)
			)
		)
		(property "Manufacturer" "Murata"
			(at 346.3 283.4 0)
			(layer "B.Fab")
			(hide yes)
			(effects
				(font
					(size 1 1)
					(thickness 0.15)
				)
				(justify mirror)
			)
		)
		(property "Val" "100n"
			(at 346.3 283.4 0)
			(layer "B.Fab")
			(hide yes)
			(effects
				(font
					(size 1 1)
					(thickness 0.15)
				)
				(justify mirror)
			)
		)
		(property "Voltage" "50V"
			(at 346.3 283.4 0)
			(layer "B.Fab")
			(hide yes)
			(effects
				(font
					(size 1 1)
					(thickness 0.15)
				)
				(justify mirror)
			)
		)
		(sheetname "DRAM + SRAM")
		(sheetfile "ram.kicad_sch")
		(attr smd)
		(fp_rect
			(start -0.925 0.47)
			(end 0.925 -0.47)
			(stroke
				(width 0.05)
				(type default)
			)
			(fill no)
			(layer "B.CrtYd")
		)
		(fp_line
			(start 0.504 0.25)
			(end 0.504 -0.248)
			(stroke
				(width 0.15)
				(type solid)
			)
			(layer "B.Fab")
		)
		(fp_line
			(start 0.504 -0.248)
			(end -0.494 -0.248)
			(stroke
				(width 0.15)
				(type solid)
			)
			(layer "B.Fab")
		)
		(fp_line
			(start -0.494 0.25)
			(end 0.504 0.25)
			(stroke
				(width 0.15)
				(type solid)
			)
			(layer "B.Fab")
		)
		(fp_line
			(start -0.494 -0.248)
			(end -0.494 0.25)
			(stroke
				(width 0.15)
				(type solid)
			)
			(layer "B.Fab")
		)
		(pad "1" smd roundrect
			(at -0.48 0 180)
			(size 0.59 0.64)
			(layers "B.Cu" "B.Mask" "B.Paste")
			(roundrect_rratio 0.25)
			(net 1 "GND")
			(pintype "passive")
		)
		(pad "2" smd roundrect
			(at 0.48 0 180)
			(size 0.59 0.64)
			(layers "B.Cu" "B.Mask" "B.Paste")
			(roundrect_rratio 0.25)
			(net 25 "+1V35")
			(pintype "passive")
		)
	)
	(footprint "antmicro-footprints:C_0402_1005Metric"
		(layer "B.Cu")
		(at 193.5 138 -90)
		(descr "Capacitor SMD 0402")
		(tags "capacitor SMD 0402")
		(property "Reference" "C95"
			(at -0.85 -1.25 90)
			(layer "B.SilkS")
			(effects
				(font
					(size 0.7 0.7)
					(thickness 0.15)
				)
				(justify left bottom mirror)
			)
		)
		(property "Value" "C_100n_0402"
			(at 0 -1.169 90)
			(layer "B.Fab")
			(effects
				(font
					(size 0.7 0.7)
					(thickness 0.15)
				)
				(justify left bottom mirror)
			)
		)
		(property "Description" "SMD Multilayer Ceramic Capacitor, 0.1 µF, 50 V, 0402 [1005 Metric], ± 10%, X5R, GRM Series"
			(at 0 0 270)
			(layer "F.Fab")
			(hide yes)
			(effects
				(font
					(size 1.27 1.27)
					(thickness 0.15)
				)
			)
		)
		(property "Author" "Antmicro"
			(at 55.5 331.5 0)
			(layer "B.Fab")
			(hide yes)
			(effects
				(font
					(size 1 1)
					(thickness 0.15)
				)
				(justify mirror)
			)
		)
		(property "Dielectric" "X5R"
			(at 55.5 331.5 0)
			(layer "B.Fab")
			(hide yes)
			(effects
				(font
					(size 1 1)
					(thickness 0.15)
				)
				(justify mirror)
			)
		)
		(property "License" "Apache-2.0"
			(at 55.5 331.5 0)
			(layer "B.Fab")
			(hide yes)
			(effects
				(font
					(size 1 1)
					(thickness 0.15)
				)
				(justify mirror)
			)
		)
		(property "MPN" "GRM155R61H104KE14D"
			(at 55.5 331.5 0)
			(layer "B.Fab")
			(hide yes)
			(effects
				(font
					(size 1 1)
					(thickness 0.15)
				)
				(justify mirror)
			)
		)
		(property "Manufacturer" "Murata"
			(at 55.5 331.5 0)
			(layer "B.Fab")
			(hide yes)
			(effects
				(font
					(size 1 1)
					(thickness 0.15)
				)
				(justify mirror)
			)
		)
		(property "Val" "100n"
			(at 55.5 331.5 0)
			(layer "B.Fab")
			(hide yes)
			(effects
				(font
					(size 1 1)
					(thickness 0.15)
				)
				(justify mirror)
			)
		)
		(property "Voltage" "50V"
			(at 55.5 331.5 0)
			(layer "B.Fab")
			(hide yes)
			(effects
				(font
					(size 1 1)
					(thickness 0.15)
				)
				(justify mirror)
			)
		)
		(sheetname "FPGA Bank 33 & 34")
		(sheetfile "fpga-bank-33-34.kicad_sch")
		(attr smd)
		(fp_rect
			(start -0.925 0.47)
			(end 0.925 -0.47)
			(stroke
				(width 0.05)
				(type default)
			)
			(fill no)
			(layer "B.CrtYd")
		)
		(fp_line
			(start -0.494 0.25)
			(end 0.504 0.25)
			(stroke
				(width 0.15)
				(type solid)
			)
			(layer "B.Fab")
		)
		(fp_line
			(start 0.504 0.25)
			(end 0.504 -0.248)
			(stroke
				(width 0.15)
				(type solid)
			)
			(layer "B.Fab")
		)
		(fp_line
			(start -0.494 -0.248)
			(end -0.494 0.25)
			(stroke
				(width 0.15)
				(type solid)
			)
			(layer "B.Fab")
		)
		(fp_line
			(start 0.504 -0.248)
			(end -0.494 -0.248)
			(stroke
				(width 0.15)
				(type solid)
			)
			(layer "B.Fab")
		)
		(pad "1" smd roundrect
			(at -0.48 0 270)
			(size 0.59 0.64)
			(layers "B.Cu" "B.Mask" "B.Paste")
			(roundrect_rratio 0.25)
			(net 1 "GND")
			(pintype "passive")
		)
		(pad "2" smd roundrect
			(at 0.48 0 270)
			(size 0.59 0.64)
			(layers "B.Cu" "B.Mask" "B.Paste")
			(roundrect_rratio 0.25)
			(net 26 "+1V8")
			(pintype "passive")
		)
	)
	(footprint "antmicro-footprints:C_0402_1005Metric"
		(layer "B.Cu")
		(at 191.75 132.3)
		(descr "Capacitor SMD 0402")
		(tags "capacitor SMD 0402")
		(property "Reference" "C123"
			(at 22.925 -28.1 180)
			(layer "B.SilkS")
			(effects
				(font
					(size 0.7 0.7)
					(thickness 0.15)
				)
				(justify left bottom mirror)
			)
		)
		(property "Value" "C_100n_0402"
			(at 0 -1.169 180)
			(layer "B.Fab")
			(effects
				(font
					(size 0.7 0.7)
					(thickness 0.15)
				)
				(justify left bottom mirror)
			)
		)
		(property "Description" "SMD Multilayer Ceramic Capacitor, 0.1 µF, 50 V, 0402 [1005 Metric], ± 10%, X5R, GRM Series"
			(at 0 0 0)
			(layer "F.Fab")
			(hide yes)
			(effects
				(font
					(size 1.27 1.27)
					(thickness 0.15)
				)
			)
		)
		(property "Author" "Antmicro"
			(at 0 0 0)
			(layer "B.Fab")
			(hide yes)
			(effects
				(font
					(size 1 1)
					(thickness 0.15)
				)
				(justify mirror)
			)
		)
		(property "Dielectric" "X5R"
			(at 0 0 0)
			(layer "B.Fab")
			(hide yes)
			(effects
				(font
					(size 1 1)
					(thickness 0.15)
				)
				(justify mirror)
			)
		)
		(property "License" "Apache-2.0"
			(at 0 0 0)
			(layer "B.Fab")
			(hide yes)
			(effects
				(font
					(size 1 1)
					(thickness 0.15)
				)
				(justify mirror)
			)
		)
		(property "MPN" "GRM155R61H104KE14D"
			(at 0 0 0)
			(layer "B.Fab")
			(hide yes)
			(effects
				(font
					(size 1 1)
					(thickness 0.15)
				)
				(justify mirror)
			)
		)
		(property "Manufacturer" "Murata"
			(at 0 0 0)
			(layer "B.Fab")
			(hide yes)
			(effects
				(font
					(size 1 1)
					(thickness 0.15)
				)
				(justify mirror)
			)
		)
		(property "Val" "100n"
			(at 0 0 0)
			(layer "B.Fab")
			(hide yes)
			(effects
				(font
					(size 1 1)
					(thickness 0.15)
				)
				(justify mirror)
			)
		)
		(property "Voltage" "50V"
			(at 0 0 0)
			(layer "B.Fab")
			(hide yes)
			(effects
				(font
					(size 1 1)
					(thickness 0.15)
				)
				(justify mirror)
			)
		)
		(sheetname "FPGA supply")
		(sheetfile "fpga-supply.kicad_sch")
		(attr smd)
		(fp_rect
			(start -0.925 0.47)
			(end 0.925 -0.47)
			(stroke
				(width 0.05)
				(type default)
			)
			(fill no)
			(layer "B.CrtYd")
		)
		(fp_line
			(start -0.494 -0.248)
			(end -0.494 0.25)
			(stroke
				(width 0.15)
				(type solid)
			)
			(layer "B.Fab")
		)
		(fp_line
			(start -0.494 0.25)
			(end 0.504 0.25)
			(stroke
				(width 0.15)
				(type solid)
			)
			(layer "B.Fab")
		)
		(fp_line
			(start 0.504 -0.248)
			(end -0.494 -0.248)
			(stroke
				(width 0.15)
				(type solid)
			)
			(layer "B.Fab")
		)
		(fp_line
			(start 0.504 0.25)
			(end 0.504 -0.248)
			(stroke
				(width 0.15)
				(type solid)
			)
			(layer "B.Fab")
		)
		(pad "1" smd roundrect
			(at -0.48 0)
			(size 0.59 0.64)
			(layers "B.Cu" "B.Mask" "B.Paste")
			(roundrect_rratio 0.25)
			(net 26 "+1V8")
			(pintype "passive")
		)
		(pad "2" smd roundrect
			(at 0.48 0)
			(size 0.59 0.64)
			(layers "B.Cu" "B.Mask" "B.Paste")
			(roundrect_rratio 0.25)
			(net 1 "GND")
			(pintype "passive")
		)
	)
	(footprint "antmicro-footprints:NetTie-2_SMD_Pad0.127mm"
		(layer "B.Cu")
		(at 248.501 148.4 90)
		(descr "Net tie, 2 pin, 0.127mm  SMD pads")
		(tags "net tie")
		(property "Reference" "NT7"
			(at -0.128 1.345 270)
			(layer "B.SilkS")
			(hide yes)
			(effects
				(font
					(size 0.7 0.7)
					(thickness 0.15)
				)
				(justify left bottom mirror)
			)
		)
		(property "Value" "Net-Tie_2"
			(at 0 -1.199 270)
			(layer "B.Fab")
			(effects
				(font
					(size 0.7 0.7)
					(thickness 0.15)
				)
				(justify left bottom mirror)
			)
		)
		(property "Description" "Net tie, 2 pins"
			(at 0 0 90)
			(layer "F.Fab")
			(hide yes)
			(effects
				(font
					(size 1.27 1.27)
					(thickness 0.15)
				)
			)
		)
		(property "Author" "Antmicro"
			(at 396.901 -100.101 0)
			(layer "B.Fab")
			(hide yes)
			(effects
				(font
					(size 1 1)
					(thickness 0.15)
				)
				(justify mirror)
			)
		)
		(property "License" "Apache-2.0"
			(at 396.901 -100.101 0)
			(layer "B.Fab")
			(hide yes)
			(effects
				(font
					(size 1 1)
					(thickness 0.15)
				)
				(justify mirror)
			)
		)
		(property "MPN" ""
			(at 396.901 -100.101 0)
			(layer "B.Fab")
			(hide yes)
			(effects
				(font
					(size 1 1)
					(thickness 0.15)
				)
				(justify mirror)
			)
		)
		(property "Manufacturer" ""
			(at 396.901 -100.101 0)
			(layer "B.Fab")
			(hide yes)
			(effects
				(font
					(size 1 1)
					(thickness 0.15)
				)
				(justify mirror)
			)
		)
		(sheetname "FPGA Config")
		(sheetfile "fpga-config.kicad_sch")
		(attr exclude_from_pos_files)
		(net_tie_pad_groups "1, 2")
		(fp_poly
			(pts
				(xy -0.0635 0.0635) (xy 0.0625 0.0635) (xy 0.0625 -0.0635) (xy -0.0635 -0.0635)
			)
			(stroke
				(width 0)
				(type solid)
			)
			(fill yes)
			(layer "B.Cu")
		)
		(pad "1" smd roundrect
			(at -0.127 0 270)
			(size 0.127 0.127)
			(layers "B.Cu")
			(roundrect_rratio 0.5)
			(chamfer_ratio 0)
			(chamfer top_left bottom_left)
			(net 1316 "/SUP_MCU.INITB")
			(pinfunction "1")
			(pintype "passive")
		)
		(pad "2" smd roundrect
			(at 0.126 0 90)
			(size 0.127 0.127)
			(layers "B.Cu")
			(roundrect_rratio 0.5)
			(chamfer_ratio 0)
			(chamfer top_left bottom_left)
			(net 257 "/FPGA Config/INIT_B")
			(pinfunction "2")
			(pintype "passive")
		)
	)
	(footprint "antmicro-footprints:C_0402_1005Metric"
		(layer "B.Cu")
		(at 265.401 171.8)
		(descr "Capacitor SMD 0402")
		(tags "capacitor SMD 0402")
		(property "Reference" "C272"
			(at 3.699 0.375 180)
			(layer "B.SilkS")
			(effects
				(font
					(size 0.7 0.7)
					(thickness 0.15)
				)
				(justify left bottom mirror)
			)
		)
		(property "Value" "C_100n_0402"
			(at 0 -1.169 180)
			(layer "B.Fab")
			(effects
				(font
					(size 0.7 0.7)
					(thickness 0.15)
				)
				(justify left bottom mirror)
			)
		)
		(property "Description" "SMD Multilayer Ceramic Capacitor, 0.1 µF, 50 V, 0402 [1005 Metric], ± 10%, X5R, GRM Series"
			(at 0 0 0)
			(layer "F.Fab")
			(hide yes)
			(effects
				(font
					(size 1.27 1.27)
					(thickness 0.15)
				)
			)
		)
		(property "Author" "Antmicro"
			(at 0 0 0)
			(layer "B.Fab")
			(hide yes)
			(effects
				(font
					(size 1 1)
					(thickness 0.15)
				)
				(justify mirror)
			)
		)
		(property "Dielectric" "X5R"
			(at 0 0 0)
			(layer "B.Fab")
			(hide yes)
			(effects
				(font
					(size 1 1)
					(thickness 0.15)
				)
				(justify mirror)
			)
		)
		(property "License" "Apache-2.0"
			(at 0 0 0)
			(layer "B.Fab")
			(hide yes)
			(effects
				(font
					(size 1 1)
					(thickness 0.15)
				)
				(justify mirror)
			)
		)
		(property "MPN" "GRM155R61H104KE14D"
			(at 0 0 0)
			(layer "B.Fab")
			(hide yes)
			(effects
				(font
					(size 1 1)
					(thickness 0.15)
				)
				(justify mirror)
			)
		)
		(property "Manufacturer" "Murata"
			(at 0 0 0)
			(layer "B.Fab")
			(hide yes)
			(effects
				(font
					(size 1 1)
					(thickness 0.15)
				)
				(justify mirror)
			)
		)
		(property "Val" "100n"
			(at 0 0 0)
			(layer "B.Fab")
			(hide yes)
			(effects
				(font
					(size 1 1)
					(thickness 0.15)
				)
				(justify mirror)
			)
		)
		(property "Voltage" "50V"
			(at 0 0 0)
			(layer "B.Fab")
			(hide yes)
			(effects
				(font
					(size 1 1)
					(thickness 0.15)
				)
				(justify mirror)
			)
		)
		(sheetname "HDMI + Ethernet")
		(sheetfile "hdmi-ethernet.kicad_sch")
		(attr smd)
		(fp_rect
			(start -0.925 0.47)
			(end 0.925 -0.47)
			(stroke
				(width 0.05)
				(type default)
			)
			(fill no)
			(layer "B.CrtYd")
		)
		(fp_line
			(start -0.494 -0.248)
			(end -0.494 0.25)
			(stroke
				(width 0.15)
				(type solid)
			)
			(layer "B.Fab")
		)
		(fp_line
			(start -0.494 0.25)
			(end 0.504 0.25)
			(stroke
				(width 0.15)
				(type solid)
			)
			(layer "B.Fab")
		)
		(fp_line
			(start 0.504 -0.248)
			(end -0.494 -0.248)
			(stroke
				(width 0.15)
				(type solid)
			)
			(layer "B.Fab")
		)
		(fp_line
			(start 0.504 0.25)
			(end 0.504 -0.248)
			(stroke
				(width 0.15)
				(type solid)
			)
			(layer "B.Fab")
		)
		(pad "1" smd roundrect
			(at -0.48 0)
			(size 0.59 0.64)
			(layers "B.Cu" "B.Mask" "B.Paste")
			(roundrect_rratio 0.25)
			(net 1 "GND")
			(pintype "passive")
		)
		(pad "2" smd roundrect
			(at 0.48 0)
			(size 0.59 0.64)
			(layers "B.Cu" "B.Mask" "B.Paste")
			(roundrect_rratio 0.25)
			(net 723 "/HDMI + Ethernet/ETH_CONN_SH")
			(pintype "passive")
		)
	)
)
